(kicad_pcb
	(version 20260206)
	(generator "pcbnew")
	(generator_version "10.0")
	(general
		(thickness 1.6)
		(legacy_teardrops no)
	)
	(paper "A4")
	(title_block
		(title "12092022_DA0F0TMDCD0_F0T_Management_Board_D_brd_V3_OCP.brd")
		(comment 1 "Grand Teton / footprints 467-472 of 1440")
	)
	(layers
		(0 "F.Cu" signal "TOP")
		(4 "In1.Cu" signal "GND")
		(6 "In2.Cu" signal "IN1")
		(8 "In3.Cu" signal "GND1")
		(10 "In4.Cu" signal "IN2")
		(12 "In5.Cu" signal "VCC")
		(14 "In6.Cu" signal "VCC1")
		(16 "In7.Cu" signal "IN3")
		(18 "In8.Cu" signal "GND2")
		(20 "In9.Cu" signal "IN4")
		(22 "In10.Cu" signal "GND3")
		(2 "B.Cu" signal "BOTTOM")
		(9 "F.Adhes" user "F.Adhesive")
		(11 "B.Adhes" user "B.Adhesive")
		(13 "F.Paste" user "Package Geometry/Pastemask Top")
		(15 "B.Paste" user "Package Geometry/Pastemask Bottom")
		(5 "F.SilkS" user "Ref Des/Silkscreen Top")
		(7 "B.SilkS" user "Ref Des/Silkscreen Bottom")
		(1 "F.Mask" user "Board Geometry/Soldermask Top")
		(3 "B.Mask" user "Board Geometry/Soldermask Bottom")
		(17 "Dwgs.User" user "User.Drawings")
		(19 "Cmts.User" user "User.Comments")
		(21 "Eco1.User" user "User.Eco1")
		(23 "Eco2.User" user "User.Eco2")
		(25 "Edge.Cuts" user "Board Geometry/Outline")
		(27 "Margin" user)
		(31 "F.CrtYd" user "Package Geometry/Place Bound Top")
		(29 "B.CrtYd" user "Package Geometry/Place Bound Bottom")
		(35 "F.Fab" user "Ref Des/Assembly Top")
		(33 "B.Fab" user "Ref Des/Assembly Bottom")
	)
	(footprint ""
		(layer "F.Cu")
		(at 80.755744 -37.559488 90)
		(property "Reference" "C18"
			(at 0 0 90)
			(layer "F.SilkS")
			(hide yes)
			(effects
				(font
					(size 1.27 1.27)
				)
			)
		)
		(property "Value" ""
			(at 0 0 90)
			(layer "F.Fab")
			(effects
				(font
					(size 1.27 1.27)
				)
			)
		)
		(duplicate_pad_numbers_are_jumpers no)
		(fp_line
			(start 0.7874 -0.4064)
			(end 0.7874 0.4064)
			(stroke
				(width 0.1524)
				(type default)
			)
			(layer "F.SilkS")
		)
		(fp_line
			(start -0.7874 -0.4064)
			(end 0.7874 -0.4064)
			(stroke
				(width 0.1524)
				(type default)
			)
			(layer "F.SilkS")
		)
		(fp_line
			(start 0.7874 0.4064)
			(end -0.7874 0.4064)
			(stroke
				(width 0.1524)
				(type default)
			)
			(layer "F.SilkS")
		)
		(fp_line
			(start -0.7874 0.4064)
			(end -0.7874 -0.4064)
			(stroke
				(width 0.1524)
				(type default)
			)
			(layer "F.SilkS")
		)
		(fp_line
			(start -0.12065 -0.305054)
			(end -0.12065 -0.2794)
			(stroke
				(width 0.1)
				(type default)
			)
			(layer "F.Fab")
		)
		(fp_line
			(start -0.67945 -0.305054)
			(end -0.12065 -0.305054)
			(stroke
				(width 0.1)
				(type default)
			)
			(layer "F.Fab")
		)
		(fp_line
			(start 0.67945 -0.3048)
			(end 0.67945 0.3048)
			(stroke
				(width 0.1)
				(type default)
			)
			(layer "F.Fab")
		)
		(fp_line
			(start 0.12065 -0.3048)
			(end 0.67945 -0.3048)
			(stroke
				(width 0.1)
				(type default)
			)
			(layer "F.Fab")
		)
		(fp_line
			(start 0.12065 -0.2794)
			(end 0.12065 -0.3048)
			(stroke
				(width 0.1)
				(type default)
			)
			(layer "F.Fab")
		)
		(fp_line
			(start -0.12065 -0.2794)
			(end 0.12065 -0.2794)
			(stroke
				(width 0.1)
				(type default)
			)
			(layer "F.Fab")
		)
		(fp_line
			(start 0.120396 0.2794)
			(end -0.12065 0.2794)
			(stroke
				(width 0.1)
				(type default)
			)
			(layer "F.Fab")
		)
		(fp_line
			(start -0.12065 0.2794)
			(end -0.12065 0.3048)
			(stroke
				(width 0.1)
				(type default)
			)
			(layer "F.Fab")
		)
		(fp_line
			(start 0.67945 0.3048)
			(end 0.120396 0.3048)
			(stroke
				(width 0.1)
				(type default)
			)
			(layer "F.Fab")
		)
		(fp_line
			(start 0.120396 0.3048)
			(end 0.120396 0.2794)
			(stroke
				(width 0.1)
				(type default)
			)
			(layer "F.Fab")
		)
		(fp_line
			(start -0.12065 0.3048)
			(end -0.67945 0.3048)
			(stroke
				(width 0.1)
				(type default)
			)
			(layer "F.Fab")
		)
		(fp_line
			(start -0.67945 0.3048)
			(end -0.67945 -0.305054)
			(stroke
				(width 0.1)
				(type default)
			)
			(layer "F.Fab")
		)
		(pad "1" smd circle
			(at -0.40005 0 90)
			(size 0 0)
			(layers "F.Cu" "F.Mask" "F.Paste")
			(net "P1V2_AUX")
		)
		(pad "2" smd circle
			(at 0.40005 0 90)
			(size 0 0)
			(layers "F.Cu" "F.Mask" "F.Paste")
			(net "GND")
		)
	)
	(footprint ""
		(layer "F.Cu")
		(at 15.748 -36.7792 -90)
		(property "Reference" "U53"
			(at 3.17627 1.397 0)
			(unlocked yes)
			(layer "F.SilkS")
			(effects
				(font
					(size 0.7874 0.5842)
					(thickness 0.1524)
				)
			)
		)
		(property "Value" ""
			(at 0 0 270)
			(layer "F.Fab")
			(effects
				(font
					(size 1.27 1.27)
				)
			)
		)
		(duplicate_pad_numbers_are_jumpers no)
		(fp_line
			(start -1.7018 1.1176)
			(end -1.7018 -1.1176)
			(stroke
				(width 0.1524)
				(type default)
			)
			(layer "F.SilkS")
		)
		(fp_line
			(start 1.7018 1.1176)
			(end -1.7018 1.1176)
			(stroke
				(width 0.1524)
				(type default)
			)
			(layer "F.SilkS")
		)
		(fp_line
			(start 0 -0.7112)
			(end -0.254 -1.1176)
			(stroke
				(width 0.1524)
				(type default)
			)
			(layer "F.SilkS")
		)
		(fp_line
			(start -0.254 -1.1176)
			(end -1.7018 -1.1176)
			(stroke
				(width 0.1524)
				(type default)
			)
			(layer "F.SilkS")
		)
		(fp_line
			(start 0.254 -1.1176)
			(end 0 -0.7112)
			(stroke
				(width 0.1524)
				(type default)
			)
			(layer "F.SilkS")
		)
		(fp_line
			(start 1.7018 -1.1176)
			(end 1.7018 1.1176)
			(stroke
				(width 0.1524)
				(type default)
			)
			(layer "F.SilkS")
		)
		(fp_line
			(start 1.7018 -1.1176)
			(end 0.254 -1.1176)
			(stroke
				(width 0.1524)
				(type default)
			)
			(layer "F.SilkS")
		)
		(fp_poly
			(pts
				(xy -1.8161 -0.675386) (xy -2.4003 -0.446786) (xy -2.4003 -0.878586)
			)
			(stroke
				(width 0)
				(type default)
			)
			(fill yes)
			(layer "F.SilkS")
		)
		(fp_line
			(start -1.5494 1.1176)
			(end -1.5494 -1.1176)
			(stroke
				(width 0.1)
				(type default)
			)
			(layer "F.Fab")
		)
		(fp_line
			(start 1.5494 1.1176)
			(end -1.5494 1.1176)
			(stroke
				(width 0.1)
				(type default)
			)
			(layer "F.Fab")
		)
		(fp_line
			(start -0.254 -1.1176)
			(end -1.5494 -1.1176)
			(stroke
				(width 0.1)
				(type default)
			)
			(layer "F.Fab")
		)
		(fp_line
			(start 0.254 -1.1176)
			(end -0.254 -1.1176)
			(stroke
				(width 0.1)
				(type default)
			)
			(layer "F.Fab")
		)
		(fp_line
			(start 1.5494 -1.1176)
			(end 1.5494 1.1176)
			(stroke
				(width 0.1)
				(type default)
			)
			(layer "F.Fab")
		)
		(fp_line
			(start 1.5494 -1.1176)
			(end 0.254 -1.1176)
			(stroke
				(width 0.1)
				(type default)
			)
			(layer "F.Fab")
		)
		(fp_poly
			(pts
				(xy -1.8161 -0.675386) (xy -2.4003 -0.446786) (xy -2.4003 -0.878586)
			)
			(stroke
				(width 0)
				(type default)
			)
			(fill yes)
			(layer "F.Fab")
		)
		(pad "1" smd rect
			(at -0.962406 -0.649986 180)
			(size 0.3302 1.1684)
			(layers "F.Cu" "F.Mask" "F.Paste")
			(net "PWRGD_P5V_AUX")
		)
		(pad "2" smd rect
			(at -0.962406 0 180)
			(size 0.3302 1.1684)
			(layers "F.Cu" "F.Mask" "F.Paste")
			(net "PWRGD_P1V2_AUX")
		)
		(pad "3" smd rect
			(at -0.962406 0.649986 180)
			(size 0.3302 1.1684)
			(layers "F.Cu" "F.Mask" "F.Paste")
			(net "GND")
		)
		(pad "4" smd rect
			(at 0.962406 0.649986 180)
			(size 0.3302 1.1684)
			(layers "F.Cu" "F.Mask" "F.Paste")
			(net "EN_P1V0_AUX")
		)
		(pad "5" smd rect
			(at 0.962406 -0.649986 180)
			(size 0.3302 1.1684)
			(layers "F.Cu" "F.Mask" "F.Paste")
			(net "P3V3_LDO")
		)
	)
	(footprint ""
		(layer "F.Cu")
		(at 67.5386 -28.321 90)
		(property "Reference" "R380"
			(at 0 0 90)
			(layer "F.SilkS")
			(hide yes)
			(effects
				(font
					(size 1.27 1.27)
				)
			)
		)
		(property "Value" ""
			(at 0 0 90)
			(layer "F.Fab")
			(effects
				(font
					(size 1.27 1.27)
				)
			)
		)
		(duplicate_pad_numbers_are_jumpers no)
		(fp_line
			(start 0.7874 -0.4064)
			(end 0.7874 0.4064)
			(stroke
				(width 0.1524)
				(type default)
			)
			(layer "F.SilkS")
		)
		(fp_line
			(start -0.7874 -0.4064)
			(end 0.7874 -0.4064)
			(stroke
				(width 0.1524)
				(type default)
			)
			(layer "F.SilkS")
		)
		(fp_line
			(start 0.7874 0.4064)
			(end -0.7874 0.4064)
			(stroke
				(width 0.1524)
				(type default)
			)
			(layer "F.SilkS")
		)
		(fp_line
			(start -0.7874 0.4064)
			(end -0.7874 -0.4064)
			(stroke
				(width 0.1524)
				(type default)
			)
			(layer "F.SilkS")
		)
		(fp_line
			(start -0.12065 -0.305054)
			(end -0.12065 -0.2794)
			(stroke
				(width 0.1)
				(type default)
			)
			(layer "F.Fab")
		)
		(fp_line
			(start -0.67945 -0.305054)
			(end -0.12065 -0.305054)
			(stroke
				(width 0.1)
				(type default)
			)
			(layer "F.Fab")
		)
		(fp_line
			(start 0.67945 -0.3048)
			(end 0.67945 0.3048)
			(stroke
				(width 0.1)
				(type default)
			)
			(layer "F.Fab")
		)
		(fp_line
			(start 0.12065 -0.3048)
			(end 0.67945 -0.3048)
			(stroke
				(width 0.1)
				(type default)
			)
			(layer "F.Fab")
		)
		(fp_line
			(start 0.12065 -0.2794)
			(end 0.12065 -0.3048)
			(stroke
				(width 0.1)
				(type default)
			)
			(layer "F.Fab")
		)
		(fp_line
			(start -0.12065 -0.2794)
			(end 0.12065 -0.2794)
			(stroke
				(width 0.1)
				(type default)
			)
			(layer "F.Fab")
		)
		(fp_line
			(start 0.120396 0.2794)
			(end -0.12065 0.2794)
			(stroke
				(width 0.1)
				(type default)
			)
			(layer "F.Fab")
		)
		(fp_line
			(start -0.12065 0.2794)
			(end -0.12065 0.3048)
			(stroke
				(width 0.1)
				(type default)
			)
			(layer "F.Fab")
		)
		(fp_line
			(start 0.67945 0.3048)
			(end 0.120396 0.3048)
			(stroke
				(width 0.1)
				(type default)
			)
			(layer "F.Fab")
		)
		(fp_line
			(start 0.120396 0.3048)
			(end 0.120396 0.2794)
			(stroke
				(width 0.1)
				(type default)
			)
			(layer "F.Fab")
		)
		(fp_line
			(start -0.12065 0.3048)
			(end -0.67945 0.3048)
			(stroke
				(width 0.1)
				(type default)
			)
			(layer "F.Fab")
		)
		(fp_line
			(start -0.67945 0.3048)
			(end -0.67945 -0.305054)
			(stroke
				(width 0.1)
				(type default)
			)
			(layer "F.Fab")
		)
		(pad "1" smd circle
			(at -0.40005 0 90)
			(size 0 0)
			(layers "F.Cu" "F.Mask" "F.Paste")
			(net "EN_P3V3_RGM")
		)
		(pad "2" smd circle
			(at 0.40005 0 90)
			(size 0 0)
			(layers "F.Cu" "F.Mask" "F.Paste")
			(net "EN_P3V3_RGM_R")
		)
	)
	(footprint ""
		(layer "F.Cu")
		(at 85.471 -76.6572 90)
		(property "Reference" "R877"
			(at 0 0 90)
			(layer "F.SilkS")
			(hide yes)
			(effects
				(font
					(size 1.27 1.27)
				)
			)
		)
		(property "Value" ""
			(at 0 0 90)
			(layer "F.Fab")
			(effects
				(font
					(size 1.27 1.27)
				)
			)
		)
		(duplicate_pad_numbers_are_jumpers no)
		(fp_line
			(start 0.7874 -0.4064)
			(end 0.7874 0.4064)
			(stroke
				(width 0.1524)
				(type default)
			)
			(layer "F.SilkS")
		)
		(fp_line
			(start -0.7874 -0.4064)
			(end 0.7874 -0.4064)
			(stroke
				(width 0.1524)
				(type default)
			)
			(layer "F.SilkS")
		)
		(fp_line
			(start 0.7874 0.4064)
			(end -0.7874 0.4064)
			(stroke
				(width 0.1524)
				(type default)
			)
			(layer "F.SilkS")
		)
		(fp_line
			(start -0.7874 0.4064)
			(end -0.7874 -0.4064)
			(stroke
				(width 0.1524)
				(type default)
			)
			(layer "F.SilkS")
		)
		(fp_line
			(start -0.12065 -0.305054)
			(end -0.12065 -0.2794)
			(stroke
				(width 0.1)
				(type default)
			)
			(layer "F.Fab")
		)
		(fp_line
			(start -0.67945 -0.305054)
			(end -0.12065 -0.305054)
			(stroke
				(width 0.1)
				(type default)
			)
			(layer "F.Fab")
		)
		(fp_line
			(start 0.67945 -0.3048)
			(end 0.67945 0.3048)
			(stroke
				(width 0.1)
				(type default)
			)
			(layer "F.Fab")
		)
		(fp_line
			(start 0.12065 -0.3048)
			(end 0.67945 -0.3048)
			(stroke
				(width 0.1)
				(type default)
			)
			(layer "F.Fab")
		)
		(fp_line
			(start 0.12065 -0.2794)
			(end 0.12065 -0.3048)
			(stroke
				(width 0.1)
				(type default)
			)
			(layer "F.Fab")
		)
		(fp_line
			(start -0.12065 -0.2794)
			(end 0.12065 -0.2794)
			(stroke
				(width 0.1)
				(type default)
			)
			(layer "F.Fab")
		)
		(fp_line
			(start 0.120396 0.2794)
			(end -0.12065 0.2794)
			(stroke
				(width 0.1)
				(type default)
			)
			(layer "F.Fab")
		)
		(fp_line
			(start -0.12065 0.2794)
			(end -0.12065 0.3048)
			(stroke
				(width 0.1)
				(type default)
			)
			(layer "F.Fab")
		)
		(fp_line
			(start 0.67945 0.3048)
			(end 0.120396 0.3048)
			(stroke
				(width 0.1)
				(type default)
			)
			(layer "F.Fab")
		)
		(fp_line
			(start 0.120396 0.3048)
			(end 0.120396 0.2794)
			(stroke
				(width 0.1)
				(type default)
			)
			(layer "F.Fab")
		)
		(fp_line
			(start -0.12065 0.3048)
			(end -0.67945 0.3048)
			(stroke
				(width 0.1)
				(type default)
			)
			(layer "F.Fab")
		)
		(fp_line
			(start -0.67945 0.3048)
			(end -0.67945 -0.305054)
			(stroke
				(width 0.1)
				(type default)
			)
			(layer "F.Fab")
		)
		(pad "1" smd circle
			(at -0.40005 0 90)
			(size 0 0)
			(layers "F.Cu" "F.Mask" "F.Paste")
			(net "PWRGD_P1V2_AUX_R")
		)
		(pad "2" smd circle
			(at 0.40005 0 90)
			(size 0 0)
			(layers "F.Cu" "F.Mask" "F.Paste")
			(net "PWRGD_P1V2_AUX_R2")
		)
	)
	(footprint ""
		(layer "F.Cu")
		(at 19.812 -65.8368)
		(property "Reference" "R737"
			(at 0 0 0)
			(layer "F.SilkS")
			(hide yes)
			(effects
				(font
					(size 1.27 1.27)
				)
			)
		)
		(property "Value" ""
			(at 0 0 0)
			(layer "F.Fab")
			(effects
				(font
					(size 1.27 1.27)
				)
			)
		)
		(duplicate_pad_numbers_are_jumpers no)
		(fp_line
			(start -0.7874 -0.4064)
			(end 0.7874 -0.4064)
			(stroke
				(width 0.1524)
				(type default)
			)
			(layer "F.SilkS")
		)
		(fp_line
			(start -0.7874 0.4064)
			(end -0.7874 -0.4064)
			(stroke
				(width 0.1524)
				(type default)
			)
			(layer "F.SilkS")
		)
		(fp_line
			(start 0.7874 -0.4064)
			(end 0.7874 0.4064)
			(stroke
				(width 0.1524)
				(type default)
			)
			(layer "F.SilkS")
		)
		(fp_line
			(start 0.7874 0.4064)
			(end -0.7874 0.4064)
			(stroke
				(width 0.1524)
				(type default)
			)
			(layer "F.SilkS")
		)
		(fp_line
			(start -0.67945 -0.305054)
			(end -0.12065 -0.305054)
			(stroke
				(width 0.1)
				(type default)
			)
			(layer "F.Fab")
		)
		(fp_line
			(start -0.67945 0.3048)
			(end -0.67945 -0.305054)
			(stroke
				(width 0.1)
				(type default)
			)
			(layer "F.Fab")
		)
		(fp_line
			(start -0.12065 -0.305054)
			(end -0.12065 -0.2794)
			(stroke
				(width 0.1)
				(type default)
			)
			(layer "F.Fab")
		)
		(fp_line
			(start -0.12065 -0.2794)
			(end 0.12065 -0.2794)
			(stroke
				(width 0.1)
				(type default)
			)
			(layer "F.Fab")
		)
		(fp_line
			(start -0.12065 0.2794)
			(end -0.12065 0.3048)
			(stroke
				(width 0.1)
				(type default)
			)
			(layer "F.Fab")
		)
		(fp_line
			(start -0.12065 0.3048)
			(end -0.67945 0.3048)
			(stroke
				(width 0.1)
				(type default)
			)
			(layer "F.Fab")
		)
		(fp_line
			(start 0.120396 0.2794)
			(end -0.12065 0.2794)
			(stroke
				(width 0.1)
				(type default)
			)
			(layer "F.Fab")
		)
		(fp_line
			(start 0.120396 0.3048)
			(end 0.120396 0.2794)
			(stroke
				(width 0.1)
				(type default)
			)
			(layer "F.Fab")
		)
		(fp_line
			(start 0.12065 -0.3048)
			(end 0.67945 -0.3048)
			(stroke
				(width 0.1)
				(type default)
			)
			(layer "F.Fab")
		)
		(fp_line
			(start 0.12065 -0.2794)
			(end 0.12065 -0.3048)
			(stroke
				(width 0.1)
				(type default)
			)
			(layer "F.Fab")
		)
		(fp_line
			(start 0.67945 -0.3048)
			(end 0.67945 0.3048)
			(stroke
				(width 0.1)
				(type default)
			)
			(layer "F.Fab")
		)
		(fp_line
			(start 0.67945 0.3048)
			(end 0.120396 0.3048)
			(stroke
				(width 0.1)
				(type default)
			)
			(layer "F.Fab")
		)
		(pad "1" smd circle
			(at -0.40005 0)
			(size 0 0)
			(layers "F.Cu" "F.Mask" "F.Paste")
			(net "P3V3_AUX")
		)
		(pad "2" smd circle
			(at 0.40005 0)
			(size 0 0)
			(layers "F.Cu" "F.Mask" "F.Paste")
			(net "SPA_SIN_SW_BUF")
		)
	)
	(footprint ""
		(layer "F.Cu")
		(at 78.000098 -74.476356 90)
		(property "Reference" "R616"
			(at 0 0 90)
			(layer "F.SilkS")
			(hide yes)
			(effects
				(font
					(size 1.27 1.27)
				)
			)
		)
		(property "Value" ""
			(at 0 0 90)
			(layer "F.Fab")
			(effects
				(font
					(size 1.27 1.27)
				)
			)
		)
		(duplicate_pad_numbers_are_jumpers no)
		(fp_line
			(start 0.7874 -0.4064)
			(end 0.7874 0.4064)
			(stroke
				(width 0.1524)
				(type default)
			)
			(layer "F.SilkS")
		)
		(fp_line
			(start -0.7874 -0.4064)
			(end 0.7874 -0.4064)
			(stroke
				(width 0.1524)
				(type default)
			)
			(layer "F.SilkS")
		)
		(fp_line
			(start 0.7874 0.4064)
			(end -0.7874 0.4064)
			(stroke
				(width 0.1524)
				(type default)
			)
			(layer "F.SilkS")
		)
		(fp_line
			(start -0.7874 0.4064)
			(end -0.7874 -0.4064)
			(stroke
				(width 0.1524)
				(type default)
			)
			(layer "F.SilkS")
		)
		(fp_line
			(start -0.12065 -0.305054)
			(end -0.12065 -0.2794)
			(stroke
				(width 0.1)
				(type default)
			)
			(layer "F.Fab")
		)
		(fp_line
			(start -0.67945 -0.305054)
			(end -0.12065 -0.305054)
			(stroke
				(width 0.1)
				(type default)
			)
			(layer "F.Fab")
		)
		(fp_line
			(start 0.67945 -0.3048)
			(end 0.67945 0.3048)
			(stroke
				(width 0.1)
				(type default)
			)
			(layer "F.Fab")
		)
		(fp_line
			(start 0.12065 -0.3048)
			(end 0.67945 -0.3048)
			(stroke
				(width 0.1)
				(type default)
			)
			(layer "F.Fab")
		)
		(fp_line
			(start 0.12065 -0.2794)
			(end 0.12065 -0.3048)
			(stroke
				(width 0.1)
				(type default)
			)
			(layer "F.Fab")
		)
		(fp_line
			(start -0.12065 -0.2794)
			(end 0.12065 -0.2794)
			(stroke
				(width 0.1)
				(type default)
			)
			(layer "F.Fab")
		)
		(fp_line
			(start 0.120396 0.2794)
			(end -0.12065 0.2794)
			(stroke
				(width 0.1)
				(type default)
			)
			(layer "F.Fab")
		)
		(fp_line
			(start -0.12065 0.2794)
			(end -0.12065 0.3048)
			(stroke
				(width 0.1)
				(type default)
			)
			(layer "F.Fab")
		)
		(fp_line
			(start 0.67945 0.3048)
			(end 0.120396 0.3048)
			(stroke
				(width 0.1)
				(type default)
			)
			(layer "F.Fab")
		)
		(fp_line
			(start 0.120396 0.3048)
			(end 0.120396 0.2794)
			(stroke
				(width 0.1)
				(type default)
			)
			(layer "F.Fab")
		)
		(fp_line
			(start -0.12065 0.3048)
			(end -0.67945 0.3048)
			(stroke
				(width 0.1)
				(type default)
			)
			(layer "F.Fab")
		)
		(fp_line
			(start -0.67945 0.3048)
			(end -0.67945 -0.305054)
			(stroke
				(width 0.1)
				(type default)
			)
			(layer "F.Fab")
		)
		(pad "1" smd circle
			(at -0.40005 0 90)
			(size 0 0)
			(layers "F.Cu" "F.Mask" "F.Paste")
			(net "FM_JTAG_TCK_MUX_BMC_SEL_R")
		)
		(pad "2" smd circle
			(at 0.40005 0 90)
			(size 0 0)
			(layers "F.Cu" "F.Mask" "F.Paste")
			(net "FM_JTAG_TCK_MUX_BMC_SEL")
		)
	)
)
